# S9S_MB_2U (Grand Teton) — schematic netlist excerpt (pin names and nets, part order shuffled) for the footprints in the layout excerpt that follows; sources: Cadence DE-HDL packaged netlist, KiCad conversion of 03242023_DA0F0TMBIJ0_F0T_Motherboard_J_brd_V01_OCP.brd

R4071  Q_RES  10K 1% EMPTY  pkg 0402LF  page 242 : A = P12V_AUX ; B = P12V_SCM_EN_G

PU79  RS53318LR  IC  pkg QFN21_4X3  page 281
  BST  = SW_PVPP_HBM_CPU0_BST
  AGND  = GND
  CS  = PVPP_HBM_CPU0_CS
  MODE  = PVPP_HBM_CPU0_MODE
  REF  = PVPP_HBM_CPU0_REF
  RTN  = SH_PVPP_HBM_CPU0_N
  FB  = PVPP_HBM_CPU0_FB
  EN  = FM_PVPP_HBM_CPU0_EN
  PGOOD  = PWRGD_PVPP_HBM_CPU0_R
  VIN1  = SW_P12V_PVCCIN_CPU0_FLT
  PGND  = GND
  VCC  = PVPP_HBM_CPU0_VCC
  SW  = SW_PVPP_HBM_CPU0_SW
  VIN2  = SW_P12V_PVCCIN_CPU0_FLT

(kicad_pcb
	(version 20260206)
	(generator "pcbnew")
	(generator_version "10.0")
	(general
		(thickness 1.6)
		(legacy_teardrops no)
	)
	(paper "A4")
	(title_block
		(title "03242023_DA0F0TMBIJ0_F0T_Motherboard_J_brd_V01_OCP.brd")
		(comment 1 "Grand Teton / footprints 3240-3241 of 6105")
	)
	(layers
		(0 "F.Cu" signal "TOP")
		(4 "In1.Cu" signal "GND")
		(6 "In2.Cu" signal "IN1")
		(8 "In3.Cu" signal "GND1")
		(10 "In4.Cu" signal "IN2")
		(12 "In5.Cu" signal "GND2")
		(14 "In6.Cu" signal "IN3")
		(16 "In7.Cu" signal "GND3")
		(18 "In8.Cu" signal "VCC")
		(20 "In9.Cu" signal "VCC1")
		(22 "In10.Cu" signal "GND4")
		(24 "In11.Cu" signal "IN4")
		(26 "In12.Cu" signal "GND5")
		(28 "In13.Cu" signal "IN5")
		(30 "In14.Cu" signal "GND6")
		(32 "In15.Cu" signal "IN6")
		(34 "In16.Cu" signal "GND7")
		(2 "B.Cu" signal "BOTTOM")
		(9 "F.Adhes" user "F.Adhesive")
		(11 "B.Adhes" user "B.Adhesive")
		(13 "F.Paste" user "Package Geometry/Pastemask Top")
		(15 "B.Paste" user "Package Geometry/Pastemask Bottom")
		(5 "F.SilkS" user "Ref Des/Silkscreen Top")
		(7 "B.SilkS" user "Ref Des/Silkscreen Bottom")
		(1 "F.Mask" user "Board Geometry/Soldermask Top")
		(3 "B.Mask" user "Board Geometry/Soldermask Bottom")
		(17 "Dwgs.User" user "User.Drawings")
		(19 "Cmts.User" user "User.Comments")
		(21 "Eco1.User" user "User.Eco1")
		(23 "Eco2.User" user "User.Eco2")
		(25 "Edge.Cuts" user "Board Geometry/Outline")
		(27 "Margin" user)
		(31 "F.CrtYd" user "Package Geometry/Place Bound Top")
		(29 "B.CrtYd" user "Package Geometry/Place Bound Bottom")
		(35 "F.Fab" user "Ref Des/Assembly Top")
		(33 "B.Fab" user "Ref Des/Assembly Bottom")
	)
	(footprint ""
		(layer "F.Cu")
		(at 373.654828 -358.460548)
		(property "Reference" "PU79"
			(at 2.394966 2.31775 0)
			(unlocked yes)
			(layer "F.SilkS")
			(effects
				(font
					(size 0.7874 0.5842)
					(thickness 0.1524)
				)
				(justify left)
			)
		)
		(property "Value" ""
			(at 0 0 0)
			(layer "F.Fab")
			(effects
				(font
					(size 1.27 1.27)
				)
			)
		)
		(duplicate_pad_numbers_are_jumpers no)
		(fp_line
			(start -1.549908 -2.050034)
			(end -1.549908 -1.9812)
			(stroke
				(width 0.1524)
				(type default)
			)
			(layer "F.SilkS")
		)
		(fp_line
			(start -1.549908 1.9812)
			(end -1.549908 2.050034)
			(stroke
				(width 0.1524)
				(type default)
			)
			(layer "F.SilkS")
		)
		(fp_line
			(start -1.549908 2.050034)
			(end -0.5842 2.050034)
			(stroke
				(width 0.1524)
				(type default)
			)
			(layer "F.SilkS")
		)
		(fp_line
			(start -0.5842 -2.050034)
			(end -1.549908 -2.050034)
			(stroke
				(width 0.1524)
				(type default)
			)
			(layer "F.SilkS")
		)
		(fp_line
			(start 0 2.050034)
			(end 1.549908 2.050034)
			(stroke
				(width 0.1524)
				(type default)
			)
			(layer "F.SilkS")
		)
		(fp_line
			(start 1.549908 -2.050034)
			(end 0.5842 -2.050034)
			(stroke
				(width 0.1524)
				(type default)
			)
			(layer "F.SilkS")
		)
		(fp_line
			(start 1.549908 -1.9812)
			(end 1.549908 -2.050034)
			(stroke
				(width 0.1524)
				(type default)
			)
			(layer "F.SilkS")
		)
		(fp_line
			(start 1.549908 2.050034)
			(end 1.549908 1.9304)
			(stroke
				(width 0.1524)
				(type default)
			)
			(layer "F.SilkS")
		)
		(fp_poly
			(pts
				(xy -3.216402 -2.222246) (xy -3.216402 -1.206246) (xy -2.200402 -1.714246)
			)
			(stroke
				(width 0)
				(type default)
			)
			(fill yes)
			(layer "F.SilkS")
		)
		(fp_line
			(start -1.549908 -2.050034)
			(end -1.549908 2.050034)
			(stroke
				(width 0.1)
				(type default)
			)
			(layer "F.Fab")
		)
		(fp_line
			(start -1.549908 2.050034)
			(end 1.549908 2.050034)
			(stroke
				(width 0.1)
				(type default)
			)
			(layer "F.Fab")
		)
		(fp_line
			(start 1.549908 -2.050034)
			(end -1.549908 -2.050034)
			(stroke
				(width 0.1)
				(type default)
			)
			(layer "F.Fab")
		)
		(fp_line
			(start 1.549908 2.050034)
			(end 1.549908 -2.050034)
			(stroke
				(width 0.1)
				(type default)
			)
			(layer "F.Fab")
		)
		(fp_poly
			(pts
				(xy -2.9464 -2.208022) (xy -2.9464 -1.192022) (xy -1.9304 -1.700022)
			)
			(stroke
				(width 0)
				(type default)
			)
			(fill yes)
			(layer "F.Fab")
		)
		(pad "1" smd circle
			(at -1.35001 -1.700022)
			(size 0 0)
			(layers "F.Cu" "F.Mask" "F.Paste")
			(net "SW_PVPP_HBM_CPU0_BST")
		)
		(pad "2" smd rect
			(at -1.400048 -1.199896 90)
			(size 0.1778 0.8128)
			(layers "F.Cu" "F.Mask" "F.Paste")
			(net "GND")
		)
		(pad "3" smd rect
			(at -1.400048 -0.8001 90)
			(size 0.1778 0.8128)
			(layers "F.Cu" "F.Mask" "F.Paste")
			(net "PVPP_HBM_CPU0_CS")
		)
		(pad "4" smd rect
			(at -1.400048 -0.40005 90)
			(size 0.1778 0.8128)
			(layers "F.Cu" "F.Mask" "F.Paste")
			(net "PVPP_HBM_CPU0_MODE")
		)
		(pad "5" smd rect
			(at -1.400048 0 90)
			(size 0.1778 0.8128)
			(layers "F.Cu" "F.Mask" "F.Paste")
			(net "PVPP_HBM_CPU0_REF")
		)
		(pad "6" smd rect
			(at -1.400048 0.40005 90)
			(size 0.1778 0.8128)
			(layers "F.Cu" "F.Mask" "F.Paste")
			(net "SH_PVPP_HBM_CPU0_N")
		)
		(pad "7" smd rect
			(at -1.400048 0.8001 90)
			(size 0.1778 0.8128)
			(layers "F.Cu" "F.Mask" "F.Paste")
			(net "PVPP_HBM_CPU0_FB")
		)
		(pad "8" smd rect
			(at -1.400048 1.199896 90)
			(size 0.1778 0.8128)
			(layers "F.Cu" "F.Mask" "F.Paste")
			(net "FM_PVPP_HBM_CPU0_EN")
		)
		(pad "9" smd rect
			(at -1.400048 1.700022 90)
			(size 0.3048 0.8128)
			(layers "F.Cu" "F.Mask" "F.Paste")
			(net "PWRGD_PVPP_HBM_CPU0_R")
		)
		(pad "10" smd rect
			(at -0.299974 1.299972)
			(size 0.3048 2.0066)
			(layers "F.Cu" "F.Mask" "F.Paste")
			(net "SW_P12V_PVCCIN_CPU0_FLT")
		)
		(pad "11_18" smd circle
			(at 1.175004 0.275082)
			(size 0 0)
			(layers "F.Cu" "F.Mask" "F.Paste")
			(net "GND")
		)
		(pad "19" smd rect
			(at 1.400048 -1.700022 270)
			(size 0.3048 0.8128)
			(layers "F.Cu" "F.Mask" "F.Paste")
			(net "PVPP_HBM_CPU0_VCC")
		)
		(pad "20" smd rect
			(at 0.299974 -1.299972)
			(size 0.3048 2.0066)
			(layers "F.Cu" "F.Mask" "F.Paste")
			(net "SW_PVPP_HBM_CPU0_SW")
		)
		(pad "21" smd rect
			(at -0.299974 -1.299972)
			(size 0.3048 2.0066)
			(layers "F.Cu" "F.Mask" "F.Paste")
			(net "SW_P12V_PVCCIN_CPU0_FLT")
		)
	)
	(footprint ""
		(layer "F.Cu")
		(at 190.4238 -42.554398)
		(property "Reference" "R4071"
			(at 0 0 0)
			(layer "F.SilkS")
			(hide yes)
			(effects
				(font
					(size 1.27 1.27)
				)
			)
		)
		(property "Value" ""
			(at 0 0 0)
			(layer "F.Fab")
			(effects
				(font
					(size 1.27 1.27)
				)
			)
		)
		(duplicate_pad_numbers_are_jumpers no)
		(fp_line
			(start -0.7874 -0.4064)
			(end 0.7874 -0.4064)
			(stroke
				(width 0.1524)
				(type default)
			)
			(layer "F.SilkS")
		)
		(fp_line
			(start -0.7874 0.4064)
			(end -0.7874 -0.4064)
			(stroke
				(width 0.1524)
				(type default)
			)
			(layer "F.SilkS")
		)
		(fp_line
			(start 0.7874 -0.4064)
			(end 0.7874 0.4064)
			(stroke
				(width 0.1524)
				(type default)
			)
			(layer "F.SilkS")
		)
		(fp_line
			(start 0.7874 0.4064)
			(end -0.7874 0.4064)
			(stroke
				(width 0.1524)
				(type default)
			)
			(layer "F.SilkS")
		)
		(fp_line
			(start -0.67945 -0.305054)
			(end -0.12065 -0.305054)
			(stroke
				(width 0.1)
				(type default)
			)
			(layer "F.Fab")
		)
		(fp_line
			(start -0.67945 0.3048)
			(end -0.67945 -0.305054)
			(stroke
				(width 0.1)
				(type default)
			)
			(layer "F.Fab")
		)
		(fp_line
			(start -0.12065 -0.305054)
			(end -0.12065 -0.2794)
			(stroke
				(width 0.1)
				(type default)
			)
			(layer "F.Fab")
		)
		(fp_line
			(start -0.12065 -0.2794)
			(end 0.12065 -0.2794)
			(stroke
				(width 0.1)
				(type default)
			)
			(layer "F.Fab")
		)
		(fp_line
			(start -0.12065 0.2794)
			(end -0.12065 0.3048)
			(stroke
				(width 0.1)
				(type default)
			)
			(layer "F.Fab")
		)
		(fp_line
			(start -0.12065 0.3048)
			(end -0.67945 0.3048)
			(stroke
				(width 0.1)
				(type default)
			)
			(layer "F.Fab")
		)
		(fp_line
			(start 0.120396 0.2794)
			(end -0.12065 0.2794)
			(stroke
				(width 0.1)
				(type default)
			)
			(layer "F.Fab")
		)
		(fp_line
			(start 0.120396 0.3048)
			(end 0.120396 0.2794)
			(stroke
				(width 0.1)
				(type default)
			)
			(layer "F.Fab")
		)
		(fp_line
			(start 0.12065 -0.3048)
			(end 0.67945 -0.3048)
			(stroke
				(width 0.1)
				(type default)
			)
			(layer "F.Fab")
		)
		(fp_line
			(start 0.12065 -0.2794)
			(end 0.12065 -0.3048)
			(stroke
				(width 0.1)
				(type default)
			)
			(layer "F.Fab")
		)
		(fp_line
			(start 0.67945 -0.3048)
			(end 0.67945 0.3048)
			(stroke
				(width 0.1)
				(type default)
			)
			(layer "F.Fab")
		)
		(fp_line
			(start 0.67945 0.3048)
			(end 0.120396 0.3048)
			(stroke
				(width 0.1)
				(type default)
			)
			(layer "F.Fab")
		)
		(pad "1" smd circle
			(at -0.40005 0)
			(size 0 0)
			(layers "F.Cu" "F.Mask" "F.Paste")
			(net "P12V_AUX")
		)
		(pad "2" smd circle
			(at 0.40005 0)
			(size 0 0)
			(layers "F.Cu" "F.Mask" "F.Paste")
			(net "P12V_SCM_EN_G")
		)
	)
)
